(kicad_pcb
	(version 20260206)
	(generator "pcbnew")
	(generator_version "10.0")
	(general
		(thickness 1.6)
		(legacy_teardrops no)
	)
	(paper "A4")
	(title_block
		(title "04192023_DAF0TMB3IC0_F0TG_MB_C_brd_V02_OCP.brd")
		(comment 1 "Grand Teton / footprint 3721 of 8354 (J67), pads 114-226 of 291")
	)
	(layers
		(0 "F.Cu" signal "TOP")
		(4 "In1.Cu" signal "GND")
		(6 "In2.Cu" signal "IN1")
		(8 "In3.Cu" signal "GND1")
		(10 "In4.Cu" signal "IN2")
		(12 "In5.Cu" signal "GND2")
		(14 "In6.Cu" signal "IN3")
		(16 "In7.Cu" signal "GND3")
		(18 "In8.Cu" signal "VCC")
		(20 "In9.Cu" signal "VCC1")
		(22 "In10.Cu" signal "GND4")
		(24 "In11.Cu" signal "IN4")
		(26 "In12.Cu" signal "GND5")
		(28 "In13.Cu" signal "IN5")
		(30 "In14.Cu" signal "GND6")
		(32 "In15.Cu" signal "IN6")
		(34 "In16.Cu" signal "GND7")
		(2 "B.Cu" signal "BOTTOM")
		(9 "F.Adhes" user "F.Adhesive")
		(11 "B.Adhes" user "B.Adhesive")
		(13 "F.Paste" user "Package Geometry/Pastemask Top")
		(15 "B.Paste" user "Package Geometry/Pastemask Bottom")
		(5 "F.SilkS" user "Ref Des/Silkscreen Top")
		(7 "B.SilkS" user "Ref Des/Silkscreen Bottom")
		(1 "F.Mask" user "Board Geometry/Soldermask Top")
		(3 "B.Mask" user "Board Geometry/Soldermask Bottom")
		(17 "Dwgs.User" user "User.Drawings")
		(19 "Cmts.User" user "User.Comments")
		(21 "Eco1.User" user "User.Eco1")
		(23 "Eco2.User" user "User.Eco2")
		(25 "Edge.Cuts" user "Board Geometry/Outline")
		(27 "Margin" user)
		(31 "F.CrtYd" user "Package Geometry/Place Bound Top")
		(29 "B.CrtYd" user "Package Geometry/Place Bound Bottom")
		(35 "F.Fab" user "Ref Des/Assembly Top")
		(33 "B.Fab" user "Ref Des/Assembly Bottom")
	)
	(footprint ""
		(layer "F.Cu")
		(at 452.138034 -255.560068 180)
		(property "Reference" "J67"
			(at 2.380488 -81.709768 0)
			(unlocked yes)
			(layer "F.SilkS")
			(effects
				(font
					(size 0.7874 0.5842)
					(thickness 0.1524)
				)
			)
		)
		(property "Value" ""
			(at 0 0 180)
			(layer "F.Fab")
			(effects
				(font
					(size 1.27 1.27)
				)
			)
		)
		(duplicate_pad_numbers_are_jumpers no)
		(pad "114" smd rect
			(at -2.050034 37.824918 90)
			(size 0.519938 1.4986)
			(layers "F.Cu" "F.Mask" "F.Paste")
			(net "GND")
		)
		(pad "115" smd rect
			(at -2.050034 38.675056 90)
			(size 0.519938 1.4986)
			(layers "F.Cu" "F.Mask" "F.Paste")
			(net "M_L_CPU0_SB_DQS_DP<1>")
		)
		(pad "116" smd rect
			(at -2.050034 39.52494 90)
			(size 0.519938 1.4986)
			(layers "F.Cu" "F.Mask" "F.Paste")
			(net "M_L_CPU0_SB_DQS_DN<1>")
		)
		(pad "117" smd rect
			(at -2.050034 40.375078 90)
			(size 0.519938 1.4986)
			(layers "F.Cu" "F.Mask" "F.Paste")
			(net "GND")
		)
		(pad "118" smd rect
			(at -2.050034 41.224962 90)
			(size 0.519938 1.4986)
			(layers "F.Cu" "F.Mask" "F.Paste")
			(net "M_L_CPU0_SB_DQ<12>")
		)
		(pad "119" smd rect
			(at -2.050034 42.0751 90)
			(size 0.519938 1.4986)
			(layers "F.Cu" "F.Mask" "F.Paste")
			(net "GND")
		)
		(pad "120" smd rect
			(at -2.050034 42.924984 90)
			(size 0.519938 1.4986)
			(layers "F.Cu" "F.Mask" "F.Paste")
			(net "M_L_CPU0_SB_DQ<13>")
		)
		(pad "121" smd rect
			(at -2.050034 43.775122 90)
			(size 0.519938 1.4986)
			(layers "F.Cu" "F.Mask" "F.Paste")
			(net "GND")
		)
		(pad "122" smd rect
			(at -2.050034 44.625006 90)
			(size 0.519938 1.4986)
			(layers "F.Cu" "F.Mask" "F.Paste")
			(net "M_L_CPU0_SB_DQ<16>")
		)
		(pad "123" smd rect
			(at -2.050034 45.47489 90)
			(size 0.519938 1.4986)
			(layers "F.Cu" "F.Mask" "F.Paste")
			(net "GND")
		)
		(pad "124" smd rect
			(at -2.050034 46.325028 90)
			(size 0.519938 1.4986)
			(layers "F.Cu" "F.Mask" "F.Paste")
			(net "M_L_CPU0_SB_DQ<17>")
		)
		(pad "125" smd rect
			(at -2.050034 47.174912 90)
			(size 0.519938 1.4986)
			(layers "F.Cu" "F.Mask" "F.Paste")
			(net "GND")
		)
		(pad "126" smd rect
			(at -2.050034 48.02505 90)
			(size 0.519938 1.4986)
			(layers "F.Cu" "F.Mask" "F.Paste")
			(net "M_L_CPU0_SB_DQS_DP<2>")
		)
		(pad "127" smd rect
			(at -2.050034 48.874934 90)
			(size 0.519938 1.4986)
			(layers "F.Cu" "F.Mask" "F.Paste")
			(net "M_L_CPU0_SB_DQS_DN<2>")
		)
		(pad "128" smd rect
			(at -2.050034 49.725072 90)
			(size 0.519938 1.4986)
			(layers "F.Cu" "F.Mask" "F.Paste")
			(net "GND")
		)
		(pad "129" smd rect
			(at -2.050034 50.574956 90)
			(size 0.519938 1.4986)
			(layers "F.Cu" "F.Mask" "F.Paste")
			(net "M_L_CPU0_SB_DQ<20>")
		)
		(pad "130" smd rect
			(at -2.050034 51.425094 90)
			(size 0.519938 1.4986)
			(layers "F.Cu" "F.Mask" "F.Paste")
			(net "GND")
		)
		(pad "131" smd rect
			(at -2.050034 52.274978 90)
			(size 0.519938 1.4986)
			(layers "F.Cu" "F.Mask" "F.Paste")
			(net "M_L_CPU0_SB_DQ<21>")
		)
		(pad "132" smd rect
			(at -2.050034 53.125116 90)
			(size 0.519938 1.4986)
			(layers "F.Cu" "F.Mask" "F.Paste")
			(net "GND")
		)
		(pad "133" smd rect
			(at -2.050034 53.975 90)
			(size 0.519938 1.4986)
			(layers "F.Cu" "F.Mask" "F.Paste")
			(net "M_L_CPU0_SB_DQ<24>")
		)
		(pad "134" smd rect
			(at -2.050034 54.824884 90)
			(size 0.519938 1.4986)
			(layers "F.Cu" "F.Mask" "F.Paste")
			(net "GND")
		)
		(pad "135" smd rect
			(at -2.050034 55.675022 90)
			(size 0.519938 1.4986)
			(layers "F.Cu" "F.Mask" "F.Paste")
			(net "M_L_CPU0_SB_DQ<25>")
		)
		(pad "136" smd rect
			(at -2.050034 56.524906 90)
			(size 0.519938 1.4986)
			(layers "F.Cu" "F.Mask" "F.Paste")
			(net "GND")
		)
		(pad "137" smd rect
			(at -2.050034 57.375044 90)
			(size 0.519938 1.4986)
			(layers "F.Cu" "F.Mask" "F.Paste")
			(net "M_L_CPU0_SB_DQS_DP<3>")
		)
		(pad "138" smd rect
			(at -2.050034 58.224928 90)
			(size 0.519938 1.4986)
			(layers "F.Cu" "F.Mask" "F.Paste")
			(net "M_L_CPU0_SB_DQS_DN<3>")
		)
		(pad "139" smd rect
			(at -2.050034 59.075066 90)
			(size 0.519938 1.4986)
			(layers "F.Cu" "F.Mask" "F.Paste")
			(net "GND")
		)
		(pad "140" smd rect
			(at -2.050034 59.92495 90)
			(size 0.519938 1.4986)
			(layers "F.Cu" "F.Mask" "F.Paste")
			(net "M_L_CPU0_SB_DQ<28>")
		)
		(pad "141" smd rect
			(at -2.050034 60.775088 90)
			(size 0.519938 1.4986)
			(layers "F.Cu" "F.Mask" "F.Paste")
			(net "GND")
		)
		(pad "142" smd rect
			(at -2.050034 61.624972 90)
			(size 0.519938 1.4986)
			(layers "F.Cu" "F.Mask" "F.Paste")
			(net "M_L_CPU0_SB_DQ<29>")
		)
		(pad "143" smd rect
			(at -2.050034 62.47511 90)
			(size 0.519938 1.4986)
			(layers "F.Cu" "F.Mask" "F.Paste")
			(net "GND")
		)
		(pad "144" smd rect
			(at -2.050034 63.324994 90)
			(size 0.519938 1.4986)
			(layers "F.Cu" "F.Mask" "F.Paste")
			(net "Net_2404")
		)
		(pad "145" smd rect
			(at 2.050034 -63.324994 90)
			(size 0.519938 1.4986)
			(layers "F.Cu" "F.Mask" "F.Paste")
			(net "P12V_MEM_CPU0")
		)
		(pad "146" smd rect
			(at 2.050034 -62.47511 90)
			(size 0.519938 1.4986)
			(layers "F.Cu" "F.Mask" "F.Paste")
			(net "P12V_MEM_CPU0")
		)
		(pad "147" smd rect
			(at 2.050034 -61.624972 90)
			(size 0.519938 1.4986)
			(layers "F.Cu" "F.Mask" "F.Paste")
			(net "PWRGD_CHL_CPU0_DIMM")
		)
		(pad "148" smd rect
			(at 2.050034 -60.775088 90)
			(size 0.519938 1.4986)
			(layers "F.Cu" "F.Mask" "F.Paste")
			(net "PD_CHL_CPU0_DIMM_SAA")
		)
		(pad "149" smd rect
			(at 2.050034 -59.92495 90)
			(size 0.519938 1.4986)
			(layers "F.Cu" "F.Mask" "F.Paste")
			(net "Net_2405")
		)
		(pad "150" smd rect
			(at 2.050034 -59.075066 90)
			(size 0.519938 1.4986)
			(layers "F.Cu" "F.Mask" "F.Paste")
			(net "Net_2406")
		)
		(pad "151" smd rect
			(at 2.050034 -58.224928 90)
			(size 0.519938 1.4986)
			(layers "F.Cu" "F.Mask" "F.Paste")
			(net "GND")
		)
		(pad "152" smd rect
			(at 2.050034 -57.375044 90)
			(size 0.519938 1.4986)
			(layers "F.Cu" "F.Mask" "F.Paste")
			(net "M_L_CPU0_SA_DQ<2>")
		)
		(pad "153" smd rect
			(at 2.050034 -56.524906 90)
			(size 0.519938 1.4986)
			(layers "F.Cu" "F.Mask" "F.Paste")
			(net "GND")
		)
		(pad "154" smd rect
			(at 2.050034 -55.675022 90)
			(size 0.519938 1.4986)
			(layers "F.Cu" "F.Mask" "F.Paste")
			(net "M_L_CPU0_SA_DQ<3>")
		)
		(pad "155" smd rect
			(at 2.050034 -54.824884 90)
			(size 0.519938 1.4986)
			(layers "F.Cu" "F.Mask" "F.Paste")
			(net "GND")
		)
		(pad "156" smd rect
			(at 2.050034 -53.975 90)
			(size 0.519938 1.4986)
			(layers "F.Cu" "F.Mask" "F.Paste")
			(net "M_L_CPU0_SA_DQS_DN<5>")
		)
		(pad "157" smd rect
			(at 2.050034 -53.125116 90)
			(size 0.519938 1.4986)
			(layers "F.Cu" "F.Mask" "F.Paste")
			(net "M_L_CPU0_SA_DQS_DP<5>")
		)
		(pad "158" smd rect
			(at 2.050034 -52.274978 90)
			(size 0.519938 1.4986)
			(layers "F.Cu" "F.Mask" "F.Paste")
			(net "GND")
		)
		(pad "159" smd rect
			(at 2.050034 -51.425094 90)
			(size 0.519938 1.4986)
			(layers "F.Cu" "F.Mask" "F.Paste")
			(net "M_L_CPU0_SA_DQ<6>")
		)
		(pad "160" smd rect
			(at 2.050034 -50.574956 90)
			(size 0.519938 1.4986)
			(layers "F.Cu" "F.Mask" "F.Paste")
			(net "GND")
		)
		(pad "161" smd rect
			(at 2.050034 -49.725072 90)
			(size 0.519938 1.4986)
			(layers "F.Cu" "F.Mask" "F.Paste")
			(net "M_L_CPU0_SA_DQ<7>")
		)
		(pad "162" smd rect
			(at 2.050034 -48.874934 90)
			(size 0.519938 1.4986)
			(layers "F.Cu" "F.Mask" "F.Paste")
			(net "GND")
		)
		(pad "163" smd rect
			(at 2.050034 -48.02505 90)
			(size 0.519938 1.4986)
			(layers "F.Cu" "F.Mask" "F.Paste")
			(net "M_L_CPU0_SA_DQ<10>")
		)
		(pad "164" smd rect
			(at 2.050034 -47.174912 90)
			(size 0.519938 1.4986)
			(layers "F.Cu" "F.Mask" "F.Paste")
			(net "GND")
		)
		(pad "165" smd rect
			(at 2.050034 -46.325028 90)
			(size 0.519938 1.4986)
			(layers "F.Cu" "F.Mask" "F.Paste")
			(net "M_L_CPU0_SA_DQ<11>")
		)
		(pad "166" smd rect
			(at 2.050034 -45.47489 90)
			(size 0.519938 1.4986)
			(layers "F.Cu" "F.Mask" "F.Paste")
			(net "GND")
		)
		(pad "167" smd rect
			(at 2.050034 -44.625006 90)
			(size 0.519938 1.4986)
			(layers "F.Cu" "F.Mask" "F.Paste")
			(net "M_L_CPU0_SA_DQS_DN<6>")
		)
		(pad "168" smd rect
			(at 2.050034 -43.775122 90)
			(size 0.519938 1.4986)
			(layers "F.Cu" "F.Mask" "F.Paste")
			(net "M_L_CPU0_SA_DQS_DP<6>")
		)
		(pad "169" smd rect
			(at 2.050034 -42.924984 90)
			(size 0.519938 1.4986)
			(layers "F.Cu" "F.Mask" "F.Paste")
			(net "GND")
		)
		(pad "170" smd rect
			(at 2.050034 -42.0751 90)
			(size 0.519938 1.4986)
			(layers "F.Cu" "F.Mask" "F.Paste")
			(net "M_L_CPU0_SA_DQ<14>")
		)
		(pad "171" smd rect
			(at 2.050034 -41.224962 90)
			(size 0.519938 1.4986)
			(layers "F.Cu" "F.Mask" "F.Paste")
			(net "GND")
		)
		(pad "172" smd rect
			(at 2.050034 -40.375078 90)
			(size 0.519938 1.4986)
			(layers "F.Cu" "F.Mask" "F.Paste")
			(net "M_L_CPU0_SA_DQ<15>")
		)
		(pad "173" smd rect
			(at 2.050034 -39.52494 90)
			(size 0.519938 1.4986)
			(layers "F.Cu" "F.Mask" "F.Paste")
			(net "GND")
		)
		(pad "174" smd rect
			(at 2.050034 -38.675056 90)
			(size 0.519938 1.4986)
			(layers "F.Cu" "F.Mask" "F.Paste")
			(net "M_L_CPU0_SA_DQ<18>")
		)
		(pad "175" smd rect
			(at 2.050034 -37.824918 90)
			(size 0.519938 1.4986)
			(layers "F.Cu" "F.Mask" "F.Paste")
			(net "GND")
		)
		(pad "176" smd rect
			(at 2.050034 -36.975034 90)
			(size 0.519938 1.4986)
			(layers "F.Cu" "F.Mask" "F.Paste")
			(net "M_L_CPU0_SA_DQ<19>")
		)
		(pad "177" smd rect
			(at 2.050034 -36.124896 90)
			(size 0.519938 1.4986)
			(layers "F.Cu" "F.Mask" "F.Paste")
			(net "GND")
		)
		(pad "178" smd rect
			(at 2.050034 -35.275012 90)
			(size 0.519938 1.4986)
			(layers "F.Cu" "F.Mask" "F.Paste")
			(net "M_L_CPU0_SA_DQS_DN<7>")
		)
		(pad "179" smd rect
			(at 2.050034 -34.425128 90)
			(size 0.519938 1.4986)
			(layers "F.Cu" "F.Mask" "F.Paste")
			(net "M_L_CPU0_SA_DQS_DP<7>")
		)
		(pad "180" smd rect
			(at 2.050034 -33.57499 90)
			(size 0.519938 1.4986)
			(layers "F.Cu" "F.Mask" "F.Paste")
			(net "GND")
		)
		(pad "181" smd rect
			(at 2.050034 -32.725106 90)
			(size 0.519938 1.4986)
			(layers "F.Cu" "F.Mask" "F.Paste")
			(net "M_L_CPU0_SA_DQ<22>")
		)
		(pad "182" smd rect
			(at 2.050034 -31.874968 90)
			(size 0.519938 1.4986)
			(layers "F.Cu" "F.Mask" "F.Paste")
			(net "GND")
		)
		(pad "183" smd rect
			(at 2.050034 -31.025084 90)
			(size 0.519938 1.4986)
			(layers "F.Cu" "F.Mask" "F.Paste")
			(net "M_L_CPU0_SA_DQ<23>")
		)
		(pad "184" smd rect
			(at 2.050034 -30.174946 90)
			(size 0.519938 1.4986)
			(layers "F.Cu" "F.Mask" "F.Paste")
			(net "GND")
		)
		(pad "185" smd rect
			(at 2.050034 -29.325062 90)
			(size 0.519938 1.4986)
			(layers "F.Cu" "F.Mask" "F.Paste")
			(net "M_L_CPU0_SA_DQ<26>")
		)
		(pad "186" smd rect
			(at 2.050034 -28.474924 90)
			(size 0.519938 1.4986)
			(layers "F.Cu" "F.Mask" "F.Paste")
			(net "GND")
		)
		(pad "187" smd rect
			(at 2.050034 -27.62504 90)
			(size 0.519938 1.4986)
			(layers "F.Cu" "F.Mask" "F.Paste")
			(net "M_L_CPU0_SA_DQ<27>")
		)
		(pad "188" smd rect
			(at 2.050034 -26.774902 90)
			(size 0.519938 1.4986)
			(layers "F.Cu" "F.Mask" "F.Paste")
			(net "GND")
		)
		(pad "189" smd rect
			(at 2.050034 -25.925018 90)
			(size 0.519938 1.4986)
			(layers "F.Cu" "F.Mask" "F.Paste")
			(net "M_L_CPU0_SA_DQS_DN<8>")
		)
		(pad "190" smd rect
			(at 2.050034 -25.07488 90)
			(size 0.519938 1.4986)
			(layers "F.Cu" "F.Mask" "F.Paste")
			(net "M_L_CPU0_SA_DQS_DP<8>")
		)
		(pad "191" smd rect
			(at 2.050034 -24.224996 90)
			(size 0.519938 1.4986)
			(layers "F.Cu" "F.Mask" "F.Paste")
			(net "GND")
		)
		(pad "192" smd rect
			(at 2.050034 -23.375112 90)
			(size 0.519938 1.4986)
			(layers "F.Cu" "F.Mask" "F.Paste")
			(net "M_L_CPU0_SA_DQ<30>")
		)
		(pad "193" smd rect
			(at 2.050034 -22.524974 90)
			(size 0.519938 1.4986)
			(layers "F.Cu" "F.Mask" "F.Paste")
			(net "GND")
		)
		(pad "194" smd rect
			(at 2.050034 -21.67509 90)
			(size 0.519938 1.4986)
			(layers "F.Cu" "F.Mask" "F.Paste")
			(net "M_L_CPU0_SA_DQ<31>")
		)
		(pad "195" smd rect
			(at 2.050034 -20.824952 90)
			(size 0.519938 1.4986)
			(layers "F.Cu" "F.Mask" "F.Paste")
			(net "GND")
		)
		(pad "196" smd rect
			(at 2.050034 -19.975068 90)
			(size 0.519938 1.4986)
			(layers "F.Cu" "F.Mask" "F.Paste")
			(net "M_L_CPU0_SA_CB<2>")
		)
		(pad "197" smd rect
			(at 2.050034 -19.12493 90)
			(size 0.519938 1.4986)
			(layers "F.Cu" "F.Mask" "F.Paste")
			(net "GND")
		)
		(pad "198" smd rect
			(at 2.050034 -18.275046 90)
			(size 0.519938 1.4986)
			(layers "F.Cu" "F.Mask" "F.Paste")
			(net "M_L_CPU0_SA_CB<3>")
		)
		(pad "199" smd rect
			(at 2.050034 -17.424908 90)
			(size 0.519938 1.4986)
			(layers "F.Cu" "F.Mask" "F.Paste")
			(net "GND")
		)
		(pad "200" smd rect
			(at 2.050034 -16.575024 90)
			(size 0.519938 1.4986)
			(layers "F.Cu" "F.Mask" "F.Paste")
			(net "M_L_CPU0_SA_DQS_DN<9>")
		)
		(pad "201" smd rect
			(at 2.050034 -15.724886 90)
			(size 0.519938 1.4986)
			(layers "F.Cu" "F.Mask" "F.Paste")
			(net "M_L_CPU0_SA_DQS_DP<9>")
		)
		(pad "202" smd rect
			(at 2.050034 -14.875002 90)
			(size 0.519938 1.4986)
			(layers "F.Cu" "F.Mask" "F.Paste")
			(net "GND")
		)
		(pad "203" smd rect
			(at 2.050034 -14.025118 90)
			(size 0.519938 1.4986)
			(layers "F.Cu" "F.Mask" "F.Paste")
			(net "M_L_CPU0_SA_CB<6>")
		)
		(pad "204" smd rect
			(at 2.050034 -13.17498 90)
			(size 0.519938 1.4986)
			(layers "F.Cu" "F.Mask" "F.Paste")
			(net "GND")
		)
		(pad "205" smd rect
			(at 2.050034 -12.325096 90)
			(size 0.519938 1.4986)
			(layers "F.Cu" "F.Mask" "F.Paste")
			(net "M_L_CPU0_SA_CB<7>")
		)
		(pad "206" smd rect
			(at 2.050034 -11.474958 90)
			(size 0.519938 1.4986)
			(layers "F.Cu" "F.Mask" "F.Paste")
			(net "GND")
		)
		(pad "207" smd rect
			(at 2.050034 -10.625074 90)
			(size 0.519938 1.4986)
			(layers "F.Cu" "F.Mask" "F.Paste")
			(net "M_L_CPU0_RESET_N")
		)
		(pad "208" smd rect
			(at 2.050034 -9.774936 90)
			(size 0.519938 1.4986)
			(layers "F.Cu" "F.Mask" "F.Paste")
			(net "GND")
		)
		(pad "209" smd rect
			(at 2.050034 -8.925052 90)
			(size 0.519938 1.4986)
			(layers "F.Cu" "F.Mask" "F.Paste")
			(net "M_L_CPU0_SA_CS_N<1>")
		)
		(pad "210" smd rect
			(at 2.050034 -8.074914 90)
			(size 0.519938 1.4986)
			(layers "F.Cu" "F.Mask" "F.Paste")
			(net "GND")
		)
		(pad "211" smd rect
			(at 2.050034 -7.22503 90)
			(size 0.519938 1.4986)
			(layers "F.Cu" "F.Mask" "F.Paste")
			(net "M_L_CPU0_SA_CA<1>")
		)
		(pad "212" smd rect
			(at 2.050034 -6.374892 90)
			(size 0.519938 1.4986)
			(layers "F.Cu" "F.Mask" "F.Paste")
			(net "GND")
		)
		(pad "213" smd rect
			(at 2.050034 -5.525008 90)
			(size 0.519938 1.4986)
			(layers "F.Cu" "F.Mask" "F.Paste")
			(net "M_L_CPU0_SA_CA<3>")
		)
		(pad "214" smd rect
			(at 2.050034 -4.675124 90)
			(size 0.519938 1.4986)
			(layers "F.Cu" "F.Mask" "F.Paste")
			(net "GND")
		)
		(pad "215" smd rect
			(at 2.050034 -3.824986 90)
			(size 0.519938 1.4986)
			(layers "F.Cu" "F.Mask" "F.Paste")
			(net "M_L_CPU0_SA_CA<5>")
		)
		(pad "216" smd rect
			(at 2.050034 -2.975102 90)
			(size 0.519938 1.4986)
			(layers "F.Cu" "F.Mask" "F.Paste")
			(net "GND")
		)
		(pad "217" smd rect
			(at 2.050034 -2.124964 90)
			(size 0.519938 1.4986)
			(layers "F.Cu" "F.Mask" "F.Paste")
			(net "M_L_CPU0_CLK_DP<0>")
		)
		(pad "218" smd rect
			(at 2.050034 -1.27508 90)
			(size 0.519938 1.4986)
			(layers "F.Cu" "F.Mask" "F.Paste")
			(net "M_L_CPU0_CLK_DN<0>")
		)
		(pad "219" smd rect
			(at 2.050034 -0.424942 90)
			(size 0.519938 1.4986)
			(layers "F.Cu" "F.Mask" "F.Paste")
			(net "GND")
		)
		(pad "220" smd rect
			(at 2.050034 5.525008 90)
			(size 0.519938 1.4986)
			(layers "F.Cu" "F.Mask" "F.Paste")
			(net "Net_2407")
		)
		(pad "221" smd rect
			(at 2.050034 6.374892 90)
			(size 0.519938 1.4986)
			(layers "F.Cu" "F.Mask" "F.Paste")
			(net "M_L_CPU0_SB_CA<1>")
		)
		(pad "222" smd rect
			(at 2.050034 7.22503 90)
			(size 0.519938 1.4986)
			(layers "F.Cu" "F.Mask" "F.Paste")
			(net "GND")
		)
		(pad "223" smd rect
			(at 2.050034 8.074914 90)
			(size 0.519938 1.4986)
			(layers "F.Cu" "F.Mask" "F.Paste")
			(net "M_L_CPU0_SB_CA<3>")
		)
		(pad "224" smd rect
			(at 2.050034 8.925052 90)
			(size 0.519938 1.4986)
			(layers "F.Cu" "F.Mask" "F.Paste")
			(net "GND")
		)
		(pad "225" smd rect
			(at 2.050034 9.774936 90)
			(size 0.519938 1.4986)
			(layers "F.Cu" "F.Mask" "F.Paste")
			(net "M_L_CPU0_SB_CA<5>")
		)
		(pad "226" smd rect
			(at 2.050034 10.625074 90)
			(size 0.519938 1.4986)
			(layers "F.Cu" "F.Mask" "F.Paste")
			(net "GND")
		)
	)
)
